# T6G (Grand Teton) — schematic netlist excerpt (pin names and nets, part order shuffled) for the footprints in the layout excerpt that follows; sources: Cadence DE-HDL packaged netlist, KiCad conversion of 04192023_DAF0TMB3IC0_F0TG_MB_C_brd_V02_OCP.brd

C2018  Q_CAP  0.1UF 25V 10% X7R  pkg 0402  page 237 : A = P3V3 ; B = GND
R8000  Q_RES  33.2 1% CHIP  pkg 0402LF  page 81 : A = PRSNT_SWB_ISO_N ; B = PRSNT_SWB_ISO_R_N

(kicad_pcb
	(version 20260206)
	(generator "pcbnew")
	(generator_version "10.0")
	(general
		(thickness 1.6)
		(legacy_teardrops no)
	)
	(paper "A4")
	(title_block
		(title "04192023_DAF0TMB3IC0_F0TG_MB_C_brd_V02_OCP.brd")
		(comment 1 "Grand Teton / footprints 1873-1874 of 8354")
	)
	(layers
		(0 "F.Cu" signal "TOP")
		(4 "In1.Cu" signal "GND")
		(6 "In2.Cu" signal "IN1")
		(8 "In3.Cu" signal "GND1")
		(10 "In4.Cu" signal "IN2")
		(12 "In5.Cu" signal "GND2")
		(14 "In6.Cu" signal "IN3")
		(16 "In7.Cu" signal "GND3")
		(18 "In8.Cu" signal "VCC")
		(20 "In9.Cu" signal "VCC1")
		(22 "In10.Cu" signal "GND4")
		(24 "In11.Cu" signal "IN4")
		(26 "In12.Cu" signal "GND5")
		(28 "In13.Cu" signal "IN5")
		(30 "In14.Cu" signal "GND6")
		(32 "In15.Cu" signal "IN6")
		(34 "In16.Cu" signal "GND7")
		(2 "B.Cu" signal "BOTTOM")
		(9 "F.Adhes" user "F.Adhesive")
		(11 "B.Adhes" user "B.Adhesive")
		(13 "F.Paste" user "Package Geometry/Pastemask Top")
		(15 "B.Paste" user "Package Geometry/Pastemask Bottom")
		(5 "F.SilkS" user "Ref Des/Silkscreen Top")
		(7 "B.SilkS" user "Ref Des/Silkscreen Bottom")
		(1 "F.Mask" user "Board Geometry/Soldermask Top")
		(3 "B.Mask" user "Board Geometry/Soldermask Bottom")
		(17 "Dwgs.User" user "User.Drawings")
		(19 "Cmts.User" user "User.Comments")
		(21 "Eco1.User" user "User.Eco1")
		(23 "Eco2.User" user "User.Eco2")
		(25 "Edge.Cuts" user "Board Geometry/Outline")
		(27 "Margin" user)
		(31 "F.CrtYd" user "Package Geometry/Place Bound Top")
		(29 "B.CrtYd" user "Package Geometry/Place Bound Bottom")
		(35 "F.Fab" user "Ref Des/Assembly Top")
		(33 "B.Fab" user "Ref Des/Assembly Bottom")
	)
	(footprint ""
		(layer "F.Cu")
		(at 157.995366 -57.474358)
		(property "Reference" "C2018"
			(at 0 0 0)
			(layer "F.SilkS")
			(hide yes)
			(effects
				(font
					(size 1.27 1.27)
				)
			)
		)
		(property "Value" ""
			(at 0 0 0)
			(layer "F.Fab")
			(effects
				(font
					(size 1.27 1.27)
				)
			)
		)
		(duplicate_pad_numbers_are_jumpers no)
		(fp_line
			(start -0.7874 -0.4064)
			(end 0.7874 -0.4064)
			(stroke
				(width 0.1524)
				(type default)
			)
			(layer "F.SilkS")
		)
		(fp_line
			(start -0.7874 0.4064)
			(end -0.7874 -0.4064)
			(stroke
				(width 0.1524)
				(type default)
			)
			(layer "F.SilkS")
		)
		(fp_line
			(start 0.7874 -0.4064)
			(end 0.7874 0.4064)
			(stroke
				(width 0.1524)
				(type default)
			)
			(layer "F.SilkS")
		)
		(fp_line
			(start 0.7874 0.4064)
			(end -0.7874 0.4064)
			(stroke
				(width 0.1524)
				(type default)
			)
			(layer "F.SilkS")
		)
		(fp_line
			(start -0.67945 -0.305054)
			(end -0.12065 -0.305054)
			(stroke
				(width 0.1)
				(type default)
			)
			(layer "F.Fab")
		)
		(fp_line
			(start -0.67945 0.3048)
			(end -0.67945 -0.305054)
			(stroke
				(width 0.1)
				(type default)
			)
			(layer "F.Fab")
		)
		(fp_line
			(start -0.12065 -0.305054)
			(end -0.12065 -0.2794)
			(stroke
				(width 0.1)
				(type default)
			)
			(layer "F.Fab")
		)
		(fp_line
			(start -0.12065 -0.2794)
			(end 0.12065 -0.2794)
			(stroke
				(width 0.1)
				(type default)
			)
			(layer "F.Fab")
		)
		(fp_line
			(start -0.12065 0.2794)
			(end -0.12065 0.3048)
			(stroke
				(width 0.1)
				(type default)
			)
			(layer "F.Fab")
		)
		(fp_line
			(start -0.12065 0.3048)
			(end -0.67945 0.3048)
			(stroke
				(width 0.1)
				(type default)
			)
			(layer "F.Fab")
		)
		(fp_line
			(start 0.120396 0.2794)
			(end -0.12065 0.2794)
			(stroke
				(width 0.1)
				(type default)
			)
			(layer "F.Fab")
		)
		(fp_line
			(start 0.120396 0.3048)
			(end 0.120396 0.2794)
			(stroke
				(width 0.1)
				(type default)
			)
			(layer "F.Fab")
		)
		(fp_line
			(start 0.12065 -0.3048)
			(end 0.67945 -0.3048)
			(stroke
				(width 0.1)
				(type default)
			)
			(layer "F.Fab")
		)
		(fp_line
			(start 0.12065 -0.2794)
			(end 0.12065 -0.3048)
			(stroke
				(width 0.1)
				(type default)
			)
			(layer "F.Fab")
		)
		(fp_line
			(start 0.67945 -0.3048)
			(end 0.67945 0.3048)
			(stroke
				(width 0.1)
				(type default)
			)
			(layer "F.Fab")
		)
		(fp_line
			(start 0.67945 0.3048)
			(end 0.120396 0.3048)
			(stroke
				(width 0.1)
				(type default)
			)
			(layer "F.Fab")
		)
		(pad "1" smd circle
			(at -0.40005 0)
			(size 0 0)
			(layers "F.Cu" "F.Mask" "F.Paste")
			(net "P3V3")
		)
		(pad "2" smd circle
			(at 0.40005 0)
			(size 0 0)
			(layers "F.Cu" "F.Mask" "F.Paste")
			(net "GND")
		)
	)
	(footprint ""
		(layer "F.Cu")
		(at 200.914 -101.346 180)
		(property "Reference" "R8000"
			(at 0 0 180)
			(layer "F.SilkS")
			(hide yes)
			(effects
				(font
					(size 1.27 1.27)
				)
			)
		)
		(property "Value" ""
			(at 0 0 180)
			(layer "F.Fab")
			(effects
				(font
					(size 1.27 1.27)
				)
			)
		)
		(duplicate_pad_numbers_are_jumpers no)
		(fp_line
			(start 0.7874 0.4064)
			(end -0.7874 0.4064)
			(stroke
				(width 0.1524)
				(type default)
			)
			(layer "F.SilkS")
		)
		(fp_line
			(start 0.7874 -0.4064)
			(end 0.7874 0.4064)
			(stroke
				(width 0.1524)
				(type default)
			)
			(layer "F.SilkS")
		)
		(fp_line
			(start -0.7874 0.4064)
			(end -0.7874 -0.4064)
			(stroke
				(width 0.1524)
				(type default)
			)
			(layer "F.SilkS")
		)
		(fp_line
			(start -0.7874 -0.4064)
			(end 0.7874 -0.4064)
			(stroke
				(width 0.1524)
				(type default)
			)
			(layer "F.SilkS")
		)
		(fp_line
			(start 0.67945 0.3048)
			(end 0.120396 0.3048)
			(stroke
				(width 0.1)
				(type default)
			)
			(layer "F.Fab")
		)
		(fp_line
			(start 0.67945 -0.3048)
			(end 0.67945 0.3048)
			(stroke
				(width 0.1)
				(type default)
			)
			(layer "F.Fab")
		)
		(fp_line
			(start 0.12065 -0.2794)
			(end 0.12065 -0.3048)
			(stroke
				(width 0.1)
				(type default)
			)
			(layer "F.Fab")
		)
		(fp_line
			(start 0.12065 -0.3048)
			(end 0.67945 -0.3048)
			(stroke
				(width 0.1)
				(type default)
			)
			(layer "F.Fab")
		)
		(fp_line
			(start 0.120396 0.3048)
			(end 0.120396 0.2794)
			(stroke
				(width 0.1)
				(type default)
			)
			(layer "F.Fab")
		)
		(fp_line
			(start 0.120396 0.2794)
			(end -0.12065 0.2794)
			(stroke
				(width 0.1)
				(type default)
			)
			(layer "F.Fab")
		)
		(fp_line
			(start -0.12065 0.3048)
			(end -0.67945 0.3048)
			(stroke
				(width 0.1)
				(type default)
			)
			(layer "F.Fab")
		)
		(fp_line
			(start -0.12065 0.2794)
			(end -0.12065 0.3048)
			(stroke
				(width 0.1)
				(type default)
			)
			(layer "F.Fab")
		)
		(fp_line
			(start -0.12065 -0.2794)
			(end 0.12065 -0.2794)
			(stroke
				(width 0.1)
				(type default)
			)
			(layer "F.Fab")
		)
		(fp_line
			(start -0.12065 -0.305054)
			(end -0.12065 -0.2794)
			(stroke
				(width 0.1)
				(type default)
			)
			(layer "F.Fab")
		)
		(fp_line
			(start -0.67945 0.3048)
			(end -0.67945 -0.305054)
			(stroke
				(width 0.1)
				(type default)
			)
			(layer "F.Fab")
		)
		(fp_line
			(start -0.67945 -0.305054)
			(end -0.12065 -0.305054)
			(stroke
				(width 0.1)
				(type default)
			)
			(layer "F.Fab")
		)
		(pad "1" smd circle
			(at -0.40005 0 180)
			(size 0 0)
			(layers "F.Cu" "F.Mask" "F.Paste")
			(net "PRSNT_SWB_ISO_N")
		)
		(pad "2" smd circle
			(at 0.40005 0 180)
			(size 0 0)
			(layers "F.Cu" "F.Mask" "F.Paste")
			(net "PRSNT_SWB_ISO_R_N")
		)
	)
)
